(kicad_pcb
	(version 20260206)
	(generator "pcbnew")
	(generator_version "10.0")
	(general
		(thickness 1.6)
		(legacy_teardrops no)
	)
	(paper "A4")
	(title_block
		(title "Bryce Canyon_F.DPB_16315-1-OCP.brd")
		(comment 1 "Bryce Canyon / footprints 622-628 of 2223")
	)
	(layers
		(0 "F.Cu" signal "TOP")
		(4 "In1.Cu" signal "L2GND")
		(6 "In2.Cu" signal "L3")
		(8 "In3.Cu" signal "L4GND")
		(10 "In4.Cu" signal "L5")
		(12 "In5.Cu" signal "L6VCC")
		(14 "In6.Cu" signal "L7VCC")
		(16 "In7.Cu" signal "L8")
		(18 "In8.Cu" signal "L9GND")
		(20 "In9.Cu" signal "L10")
		(22 "In10.Cu" signal "L11GND")
		(2 "B.Cu" signal "BOTTOM")
		(9 "F.Adhes" user "F.Adhesive")
		(11 "B.Adhes" user "B.Adhesive")
		(13 "F.Paste" user "Package Geometry/Pastemask Top")
		(15 "B.Paste" user "Package Geometry/Pastemask Bottom")
		(5 "F.SilkS" user "Ref Des/Silkscreen Top")
		(7 "B.SilkS" user "Ref Des/Silkscreen Bottom")
		(1 "F.Mask" user "Board Geometry/Soldermask Top")
		(3 "B.Mask" user "Board Geometry/Soldermask Bottom")
		(17 "Dwgs.User" user "User.Drawings")
		(19 "Cmts.User" user "User.Comments")
		(21 "Eco1.User" user "User.Eco1")
		(23 "Eco2.User" user "User.Eco2")
		(25 "Edge.Cuts" user "Board Geometry/Outline")
		(27 "Margin" user)
		(31 "F.CrtYd" user "Package Geometry/Place Bound Top")
		(29 "B.CrtYd" user "Package Geometry/Place Bound Bottom")
		(35 "F.Fab" user "Ref Des/Assembly Top")
		(33 "B.Fab" user "Ref Des/Assembly Bottom")
	)
	(footprint ""
		(layer "F.Cu")
		(at 475.784926 -170.285918 180)
		(property "Reference" "Q137"
			(at 0 0 180)
			(layer "F.SilkS")
			(hide yes)
			(effects
				(font
					(size 1.27 1.27)
				)
			)
		)
		(property "Value" "AO4406AL-GP"
			(at -3.707384 -1.5367 180)
			(unlocked yes)
			(layer "F.Fab")
			(hide yes)
			(effects
				(font
					(size 1.016 1.016)
					(thickness 0.1524)
				)
			)
		)
		(property "Device Type" "SOIC8H69"
			(at -3.707384 -3.0607 180)
			(unlocked yes)
			(layer "F.Fab")
			(hide yes)
			(effects
				(font
					(size 1.016 1.016)
					(thickness 0.1524)
				)
			)
		)
		(duplicate_pad_numbers_are_jumpers no)
		(fp_line
			(start 2.1336 1.4224)
			(end 2.1336 -1.4224)
			(stroke
				(width 0.1524)
				(type default)
			)
			(layer "F.SilkS")
		)
		(fp_line
			(start 2.1336 -1.4224)
			(end -2.7432 -1.4224)
			(stroke
				(width 0.1524)
				(type default)
			)
			(layer "F.SilkS")
		)
		(fp_line
			(start -2.1844 -0.0508)
			(end -2.7178 0.508)
			(stroke
				(width 0.1524)
				(type default)
			)
			(layer "F.SilkS")
		)
		(fp_line
			(start -2.6289 3.4417)
			(end -2.6289 1.4732)
			(stroke
				(width 0.381)
				(type default)
			)
			(layer "F.SilkS")
		)
		(fp_line
			(start -2.7178 -0.508)
			(end -2.1844 -0.0508)
			(stroke
				(width 0.1524)
				(type default)
			)
			(layer "F.SilkS")
		)
		(fp_line
			(start -2.7432 1.4224)
			(end 2.1336 1.4224)
			(stroke
				(width 0.1524)
				(type default)
			)
			(layer "F.SilkS")
		)
		(fp_line
			(start -2.7432 1.4224)
			(end -2.6416 1.4224)
			(stroke
				(width 0.1524)
				(type default)
			)
			(layer "F.SilkS")
		)
		(fp_line
			(start -2.7432 -1.4224)
			(end -2.7432 1.4224)
			(stroke
				(width 0.1524)
				(type default)
			)
			(layer "F.SilkS")
		)
		(fp_poly
			(pts
				(xy -2.2098 -1.4224) (xy -2.2098 1.4224) (xy 2.2098 1.4224) (xy 2.2098 -1.4224)
			)
			(stroke
				(width 0)
				(type default)
			)
			(fill yes)
			(layer "F.SilkS")
		)
		(fp_rect
			(start -2.450084 2.999994)
			(end 2.450084 -2.999994)
			(stroke
				(width 0)
				(type default)
			)
			(fill no)
			(layer "F.CrtYd")
		)
		(fp_poly
			(pts
				(xy -2.8194 3.6322) (xy -2.8194 -3.6322) (xy 2.8194 -3.6322) (xy 2.8194 1.18364) (xy 2.450084 1.18364)
				(xy 2.450084 -2.999994) (xy -2.450084 -2.999994) (xy -2.450084 2.999994) (xy 2.450084 2.999994)
				(xy 2.450084 1.18618) (xy 2.8194 1.18618) (xy 2.8194 3.6322)
			)
			(stroke
				(width 0)
				(type default)
			)
			(fill no)
			(layer "F.CrtYd")
		)
		(fp_rect
			(start -2.8194 3.6322)
			(end 2.8194 -3.6322)
			(stroke
				(width 0)
				(type default)
			)
			(fill no)
			(layer "F.Fab")
		)
		(pad "1" smd rect
			(at -1.905 2.54 180)
			(size 0.635 1.651)
			(layers "F.Cu" "F.Mask" "F.Paste")
			(net "P5V_HDD23")
		)
		(pad "2" smd rect
			(at -0.635 2.54 180)
			(size 0.635 1.651)
			(layers "F.Cu" "F.Mask" "F.Paste")
			(net "P5V_HDD23")
		)
		(pad "3" smd rect
			(at 0.635 2.54 180)
			(size 0.635 1.651)
			(layers "F.Cu" "F.Mask" "F.Paste")
			(net "P5V_HDD23")
		)
		(pad "4" smd rect
			(at 1.905 2.54 180)
			(size 0.635 1.651)
			(layers "F.Cu" "F.Mask" "F.Paste")
			(net "SW_HDD_P23")
		)
		(pad "5" smd rect
			(at 1.905 -2.54 180)
			(size 0.635 1.651)
			(layers "F.Cu" "F.Mask" "F.Paste")
			(net "P5V_A_4")
		)
		(pad "6" smd rect
			(at 0.635 -2.54 180)
			(size 0.635 1.651)
			(layers "F.Cu" "F.Mask" "F.Paste")
			(net "P5V_A_4")
		)
		(pad "7" smd rect
			(at -0.635 -2.54 180)
			(size 0.635 1.651)
			(layers "F.Cu" "F.Mask" "F.Paste")
			(net "P5V_A_4")
		)
		(pad "8" smd rect
			(at -1.905 -2.54 180)
			(size 0.635 1.651)
			(layers "F.Cu" "F.Mask" "F.Paste")
			(net "P5V_A_4")
		)
	)
	(footprint ""
		(layer "F.Cu")
		(at 253.9238 -290.195)
		(property "Reference" "R6"
			(at 0 0 0)
			(layer "F.SilkS")
			(hide yes)
			(effects
				(font
					(size 1.27 1.27)
				)
			)
		)
		(property "Value" "4K7R2F-GP"
			(at 0.064008 -3.993896 0)
			(unlocked yes)
			(layer "F.Fab")
			(hide yes)
			(effects
				(font
					(size 1.016 1.016)
					(thickness 0.1524)
				)
			)
		)
		(property "Device Type" "R402H16"
			(at 0.064008 -5.517896 0)
			(unlocked yes)
			(layer "F.Fab")
			(hide yes)
			(effects
				(font
					(size 1.016 1.016)
					(thickness 0.1524)
				)
			)
		)
		(duplicate_pad_numbers_are_jumpers no)
		(fp_line
			(start -0.508 -0.9398)
			(end -0.508 0.9398)
			(stroke
				(width 0.1524)
				(type default)
			)
			(layer "F.SilkS")
		)
		(fp_line
			(start 0.508 -0.9398)
			(end -0.508 -0.9398)
			(stroke
				(width 0.1524)
				(type default)
			)
			(layer "F.SilkS")
		)
		(fp_rect
			(start -0.508 0.9398)
			(end 0.508 -0.9398)
			(stroke
				(width 0)
				(type default)
			)
			(fill no)
			(layer "F.CrtYd")
		)
		(fp_rect
			(start -0.508 0.9398)
			(end 0.508 -0.9398)
			(stroke
				(width 0)
				(type default)
			)
			(fill no)
			(layer "F.Fab")
		)
		(pad "1" smd custom
			(at 0 -0.4445)
			(size 0.1397 0.1397)
			(layers "F.Cu" "F.Mask" "F.Paste")
			(net "EEPROM_A0")
			(options
				(clearance outline)
				(anchor circle)
			)
			(primitives
				(gr_poly
					(pts
						(arc
							(start -0.1778 -0.2794)
							(mid -0.249642 -0.249642)
							(end -0.2794 -0.1778)
						)
						(arc
							(start -0.2794 0.1778)
							(mid -0.249642 0.249642)
							(end -0.1778 0.2794)
						)
						(arc
							(start 0.1778 0.2794)
							(mid 0.249642 0.249642)
							(end 0.2794 0.1778)
						)
						(arc
							(start 0.2794 -0.1778)
							(mid 0.249642 -0.249642)
							(end 0.1778 -0.2794)
						)
					)
					(width 0)
					(fill yes)
				)
			)
		)
		(pad "2" smd custom
			(at 0 0.4445)
			(size 0.1397 0.1397)
			(layers "F.Cu" "F.Mask" "F.Paste")
			(net "GND")
			(options
				(clearance outline)
				(anchor circle)
			)
			(primitives
				(gr_poly
					(pts
						(arc
							(start -0.1778 -0.2794)
							(mid -0.249642 -0.249642)
							(end -0.2794 -0.1778)
						)
						(arc
							(start -0.2794 0.1778)
							(mid -0.249642 0.249642)
							(end -0.1778 0.2794)
						)
						(arc
							(start 0.1778 0.2794)
							(mid 0.249642 0.249642)
							(end 0.2794 0.1778)
						)
						(arc
							(start 0.2794 -0.1778)
							(mid 0.249642 -0.249642)
							(end 0.1778 -0.2794)
						)
					)
					(width 0)
					(fill yes)
				)
			)
		)
	)
	(footprint ""
		(layer "F.Cu")
		(at 481.249736 -120.499886)
		(property "Reference" ""
			(at 0 0 0)
			(layer "F.SilkS")
			(hide yes)
			(effects
				(font
					(size 1.27 1.27)
				)
			)
		)
		(property "Value" "*"
			(at -4.9911 1.5494 0)
			(unlocked yes)
			(layer "F.Fab")
			(hide yes)
			(effects
				(font
					(size 1.016 1.016)
					(thickness 0.1524)
				)
			)
		)
		(duplicate_pad_numbers_are_jumpers no)
		(fp_poly
			(pts
				(arc
					(start 4.064 0)
					(mid -4.064 0)
					(end 4.064 0)
				)
			)
			(stroke
				(width 0)
				(type default)
			)
			(fill no)
			(layer "B.CrtYd")
		)
		(fp_poly
			(pts
				(arc
					(start 4.064 0)
					(mid -4.064 0)
					(end 4.064 0)
				)
			)
			(stroke
				(width 0)
				(type default)
			)
			(fill no)
			(layer "F.CrtYd")
		)
		(fp_poly
			(pts
				(arc
					(start 4.064 0)
					(mid -4.064 0)
					(end 4.064 0)
				)
			)
			(stroke
				(width 0)
				(type default)
			)
			(fill no)
			(layer "B.Fab")
		)
		(fp_poly
			(pts
				(arc
					(start 4.064 0)
					(mid -4.064 0)
					(end 4.064 0)
				)
			)
			(stroke
				(width 0)
				(type default)
			)
			(fill no)
			(layer "F.Fab")
		)
		(pad "1" thru_hole circle
			(at 0 0)
			(size 7.5184 7.5184)
			(drill oval 6.223 4.2164)
			(layers "*.Cu" "*.Mask")
			(remove_unused_layers no)
			(net "Net_59")
			(clearance -1.143)
			(thermal_gap 0.1524)
			(padstack
				(mode front_inner_back)
				(layer "Inner"
					(shape oval)
					(size 4.9276 6.9342)
					(clearance 0.1524)
				)
				(layer "B.Cu"
					(shape circle)
					(size 7.5184 7.5184)
					(clearance -1.143)
				)
			)
		)
		(zone
			(layers "F.Cu" "B.Cu" "In1.Cu" "In2.Cu" "In3.Cu" "In4.Cu" "In5.Cu" "In6.Cu"
				"In7.Cu" "In8.Cu" "In9.Cu" "In10.Cu"
			)
			(hatch none 0.5)
			(connect_pads
				(clearance 0)
			)
			(min_thickness 0.25)
			(keepout
				(tracks not_allowed)
				(vias allowed)
				(pads allowed)
				(copperpour not_allowed)
				(footprints allowed)
			)
			(placement
				(enabled no)
				(sheetname "")
			)
			(fill
				(thermal_gap 0.5)
				(thermal_bridge_width 0.5)
				(island_removal_mode 0)
			)
			(polygon
				(pts
					(arc
						(start 485.008936 -120.499886)
						(mid 477.490536 -120.499886)
						(end 485.008936 -120.499886)
					)
				)
			)
		)
	)
	(footprint ""
		(layer "F.Cu")
		(at 471.924126 -167.085518 90)
		(property "Reference" "R666"
			(at 0 0 90)
			(layer "F.SilkS")
			(hide yes)
			(effects
				(font
					(size 1.27 1.27)
				)
			)
		)
		(property "Value" "4K7R2J-2-GP"
			(at 0.064008 -3.993896 90)
			(unlocked yes)
			(layer "F.Fab")
			(hide yes)
			(effects
				(font
					(size 1.016 1.016)
					(thickness 0.1524)
				)
			)
		)
		(property "Device Type" "R402H16"
			(at 0.064008 -5.517896 90)
			(unlocked yes)
			(layer "F.Fab")
			(hide yes)
			(effects
				(font
					(size 1.016 1.016)
					(thickness 0.1524)
				)
			)
		)
		(duplicate_pad_numbers_are_jumpers no)
		(fp_line
			(start 0.508 -0.9398)
			(end -0.508 -0.9398)
			(stroke
				(width 0.1524)
				(type default)
			)
			(layer "F.SilkS")
		)
		(fp_line
			(start -0.508 -0.9398)
			(end -0.508 0.9398)
			(stroke
				(width 0.1524)
				(type default)
			)
			(layer "F.SilkS")
		)
		(fp_rect
			(start -0.508 0.9398)
			(end 0.508 -0.9398)
			(stroke
				(width 0)
				(type default)
			)
			(fill no)
			(layer "F.CrtYd")
		)
		(fp_rect
			(start -0.508 0.9398)
			(end 0.508 -0.9398)
			(stroke
				(width 0)
				(type default)
			)
			(fill no)
			(layer "F.Fab")
		)
		(pad "1" smd custom
			(at 0 -0.4445 90)
			(size 0.1397 0.1397)
			(layers "F.Cu" "F.Mask" "F.Paste")
			(net "P12V_A")
			(options
				(clearance outline)
				(anchor circle)
			)
			(primitives
				(gr_poly
					(pts
						(arc
							(start -0.1778 -0.2794)
							(mid -0.249642 -0.249642)
							(end -0.2794 -0.1778)
						)
						(arc
							(start -0.2794 0.1778)
							(mid -0.249642 0.249642)
							(end -0.1778 0.2794)
						)
						(arc
							(start 0.1778 0.2794)
							(mid 0.249642 0.249642)
							(end 0.2794 0.1778)
						)
						(arc
							(start 0.2794 -0.1778)
							(mid 0.249642 -0.249642)
							(end 0.1778 -0.2794)
						)
					)
					(width 0)
					(fill yes)
				)
			)
		)
		(pad "2" smd custom
			(at 0 0.4445 90)
			(size 0.1397 0.1397)
			(layers "F.Cu" "F.Mask" "F.Paste")
			(net "SW_HDD_P23")
			(options
				(clearance outline)
				(anchor circle)
			)
			(primitives
				(gr_poly
					(pts
						(arc
							(start -0.1778 -0.2794)
							(mid -0.249642 -0.249642)
							(end -0.2794 -0.1778)
						)
						(arc
							(start -0.2794 0.1778)
							(mid -0.249642 0.249642)
							(end -0.1778 0.2794)
						)
						(arc
							(start 0.1778 0.2794)
							(mid 0.249642 0.249642)
							(end 0.2794 0.1778)
						)
						(arc
							(start 0.2794 -0.1778)
							(mid 0.249642 -0.249642)
							(end 0.1778 -0.2794)
						)
					)
					(width 0)
					(fill yes)
				)
			)
		)
	)
	(footprint ""
		(layer "F.Cu")
		(at 256.9718 -237.49 -90)
		(property "Reference" "C29"
			(at 0 0 270)
			(layer "F.SilkS")
			(hide yes)
			(effects
				(font
					(size 1.27 1.27)
				)
			)
		)
		(property "Value" "SC1U16V3KX-5GP"
			(at 0 -2.8194 270)
			(unlocked yes)
			(layer "F.Fab")
			(hide yes)
			(effects
				(font
					(size 1.016 1.016)
					(thickness 0.1524)
				)
			)
		)
		(property "Device Type" "C603H36"
			(at 0 -4.3434 270)
			(unlocked yes)
			(layer "F.Fab")
			(hide yes)
			(effects
				(font
					(size 1.016 1.016)
					(thickness 0.1524)
				)
			)
		)
		(duplicate_pad_numbers_are_jumpers no)
		(fp_line
			(start 0.508 0)
			(end -0.508 0)
			(stroke
				(width 0.2032)
				(type default)
			)
			(layer "F.SilkS")
		)
		(fp_rect
			(start -0.5842 1.3335)
			(end 0.5842 -1.3335)
			(stroke
				(width 0)
				(type default)
			)
			(fill no)
			(layer "F.CrtYd")
		)
		(fp_rect
			(start -0.5842 1.3335)
			(end 0.5842 -1.3335)
			(stroke
				(width 0)
				(type default)
			)
			(fill no)
			(layer "F.Fab")
		)
		(pad "1" smd custom
			(at 0 -0.762 270)
			(size 0.2159 0.2159)
			(layers "F.Cu" "F.Mask" "F.Paste")
			(net "GPIO_VCC_U9")
			(options
				(clearance outline)
				(anchor circle)
			)
			(primitives
				(gr_poly
					(pts
						(arc
							(start -0.3302 -0.4318)
							(mid -0.402042 -0.402042)
							(end -0.4318 -0.3302)
						)
						(arc
							(start -0.4318 0.3302)
							(mid -0.402042 0.402042)
							(end -0.3302 0.4318)
						)
						(arc
							(start 0.3302 0.4318)
							(mid 0.402042 0.402042)
							(end 0.4318 0.3302)
						)
						(arc
							(start 0.4318 -0.3302)
							(mid 0.402042 -0.402042)
							(end 0.3302 -0.4318)
						)
					)
					(width 0)
					(fill yes)
				)
			)
		)
		(pad "2" smd custom
			(at 0 0.762 270)
			(size 0.2159 0.2159)
			(layers "F.Cu" "F.Mask" "F.Paste")
			(net "GND")
			(options
				(clearance outline)
				(anchor circle)
			)
			(primitives
				(gr_poly
					(pts
						(arc
							(start -0.3302 -0.4318)
							(mid -0.402042 -0.402042)
							(end -0.4318 -0.3302)
						)
						(arc
							(start -0.4318 0.3302)
							(mid -0.402042 0.402042)
							(end -0.3302 0.4318)
						)
						(arc
							(start 0.3302 0.4318)
							(mid 0.402042 0.402042)
							(end 0.4318 0.3302)
						)
						(arc
							(start 0.4318 -0.3302)
							(mid 0.402042 -0.402042)
							(end 0.3302 -0.4318)
						)
					)
					(width 0)
					(fill yes)
				)
			)
		)
	)
	(footprint ""
		(layer "F.Cu")
		(at 409.144978 -127.254)
		(property "Reference" "R335"
			(at 0 0 0)
			(layer "F.SilkS")
			(hide yes)
			(effects
				(font
					(size 1.27 1.27)
				)
			)
		)
		(property "Value" "130R3F-GP"
			(at -0.0254 -2.5146 0)
			(unlocked yes)
			(layer "F.Fab")
			(hide yes)
			(effects
				(font
					(size 1.016 1.016)
					(thickness 0.1524)
				)
			)
		)
		(property "Device Type" "R603H22"
			(at -0.0254 -4.0386 0)
			(unlocked yes)
			(layer "F.Fab")
			(hide yes)
			(effects
				(font
					(size 1.016 1.016)
					(thickness 0.1524)
				)
			)
		)
		(duplicate_pad_numbers_are_jumpers no)
		(fp_line
			(start -0.4826 0)
			(end -0.2032 0)
			(stroke
				(width 0.2032)
				(type default)
			)
			(layer "F.SilkS")
		)
		(fp_line
			(start 0.2032 0)
			(end 0.4826 0)
			(stroke
				(width 0.2032)
				(type default)
			)
			(layer "F.SilkS")
		)
		(fp_rect
			(start -0.5842 1.3335)
			(end 0.5842 -1.3335)
			(stroke
				(width 0)
				(type default)
			)
			(fill no)
			(layer "F.CrtYd")
		)
		(fp_rect
			(start -0.5842 1.3335)
			(end 0.5842 -1.3335)
			(stroke
				(width 0)
				(type default)
			)
			(fill no)
			(layer "F.Fab")
		)
		(pad "1" smd custom
			(at 0 -0.762)
			(size 0.2159 0.2159)
			(layers "F.Cu" "F.Mask" "F.Paste")
			(net "P5V_A_4")
			(options
				(clearance outline)
				(anchor circle)
			)
			(primitives
				(gr_poly
					(pts
						(arc
							(start -0.3302 -0.4318)
							(mid -0.402042 -0.402042)
							(end -0.4318 -0.3302)
						)
						(arc
							(start -0.4318 0.3302)
							(mid -0.402042 0.402042)
							(end -0.3302 0.4318)
						)
						(arc
							(start 0.3302 0.4318)
							(mid 0.402042 0.402042)
							(end 0.4318 0.3302)
						)
						(arc
							(start 0.4318 -0.3302)
							(mid 0.402042 -0.402042)
							(end 0.3302 -0.4318)
						)
					)
					(width 0)
					(fill yes)
				)
			)
		)
		(pad "2" smd custom
			(at 0 0.762)
			(size 0.2159 0.2159)
			(layers "F.Cu" "F.Mask" "F.Paste")
			(net "FLT_HDD21")
			(options
				(clearance outline)
				(anchor circle)
			)
			(primitives
				(gr_poly
					(pts
						(arc
							(start -0.3302 -0.4318)
							(mid -0.402042 -0.402042)
							(end -0.4318 -0.3302)
						)
						(arc
							(start -0.4318 0.3302)
							(mid -0.402042 0.402042)
							(end -0.3302 0.4318)
						)
						(arc
							(start 0.3302 0.4318)
							(mid 0.402042 0.402042)
							(end 0.4318 0.3302)
						)
						(arc
							(start 0.4318 -0.3302)
							(mid 0.402042 -0.402042)
							(end 0.3302 -0.4318)
						)
					)
					(width 0)
					(fill yes)
				)
			)
		)
	)
	(footprint ""
		(layer "F.Cu")
		(at 274.955 -272.288)
		(property "Reference" "R118"
			(at 0 0 0)
			(layer "F.SilkS")
			(hide yes)
			(effects
				(font
					(size 1.27 1.27)
				)
			)
		)
		(property "Value" "4K7R2F-GP"
			(at 0.064008 -3.993896 0)
			(unlocked yes)
			(layer "F.Fab")
			(hide yes)
			(effects
				(font
					(size 1.016 1.016)
					(thickness 0.1524)
				)
			)
		)
		(property "Device Type" "R402H16"
			(at 0.064008 -5.517896 0)
			(unlocked yes)
			(layer "F.Fab")
			(hide yes)
			(effects
				(font
					(size 1.016 1.016)
					(thickness 0.1524)
				)
			)
		)
		(duplicate_pad_numbers_are_jumpers no)
		(fp_line
			(start -0.508 -0.9398)
			(end -0.508 0.9398)
			(stroke
				(width 0.1524)
				(type default)
			)
			(layer "F.SilkS")
		)
		(fp_line
			(start 0.508 -0.9398)
			(end -0.508 -0.9398)
			(stroke
				(width 0.1524)
				(type default)
			)
			(layer "F.SilkS")
		)
		(fp_rect
			(start -0.508 0.9398)
			(end 0.508 -0.9398)
			(stroke
				(width 0)
				(type default)
			)
			(fill no)
			(layer "F.CrtYd")
		)
		(fp_rect
			(start -0.508 0.9398)
			(end 0.508 -0.9398)
			(stroke
				(width 0)
				(type default)
			)
			(fill no)
			(layer "F.Fab")
		)
		(pad "1" smd custom
			(at 0 -0.4445)
			(size 0.1397 0.1397)
			(layers "F.Cu" "F.Mask" "F.Paste")
			(net "IO_EXP1_HDD_FAULT_A2")
			(options
				(clearance outline)
				(anchor circle)
			)
			(primitives
				(gr_poly
					(pts
						(arc
							(start -0.1778 -0.2794)
							(mid -0.249642 -0.249642)
							(end -0.2794 -0.1778)
						)
						(arc
							(start -0.2794 0.1778)
							(mid -0.249642 0.249642)
							(end -0.1778 0.2794)
						)
						(arc
							(start 0.1778 0.2794)
							(mid 0.249642 0.249642)
							(end 0.2794 0.1778)
						)
						(arc
							(start 0.2794 -0.1778)
							(mid 0.249642 -0.249642)
							(end 0.1778 -0.2794)
						)
					)
					(width 0)
					(fill yes)
				)
			)
		)
		(pad "2" smd custom
			(at 0 0.4445)
			(size 0.1397 0.1397)
			(layers "F.Cu" "F.Mask" "F.Paste")
			(net "GND")
			(options
				(clearance outline)
				(anchor circle)
			)
			(primitives
				(gr_poly
					(pts
						(arc
							(start -0.1778 -0.2794)
							(mid -0.249642 -0.249642)
							(end -0.2794 -0.1778)
						)
						(arc
							(start -0.2794 0.1778)
							(mid -0.249642 0.249642)
							(end -0.1778 0.2794)
						)
						(arc
							(start 0.1778 0.2794)
							(mid 0.249642 0.249642)
							(end 0.2794 0.1778)
						)
						(arc
							(start 0.2794 -0.1778)
							(mid 0.249642 -0.249642)
							(end 0.1778 -0.2794)
						)
					)
					(width 0)
					(fill yes)
				)
			)
		)
	)
)
